(kicad_pcb
	(version 20260206)
	(generator "pcbnew")
	(generator_version "10.0")
	(general
		(thickness 1.6)
		(legacy_teardrops no)
	)
	(paper "A4")
	(title_block
		(title "12092022_DA0F0TMDCD0_F0T_Management_Board_D_brd_V3_OCP.brd")
		(comment 1 "Grand Teton / footprints 1351-1356 of 1440")
	)
	(layers
		(0 "F.Cu" signal "TOP")
		(4 "In1.Cu" signal "GND")
		(6 "In2.Cu" signal "IN1")
		(8 "In3.Cu" signal "GND1")
		(10 "In4.Cu" signal "IN2")
		(12 "In5.Cu" signal "VCC")
		(14 "In6.Cu" signal "VCC1")
		(16 "In7.Cu" signal "IN3")
		(18 "In8.Cu" signal "GND2")
		(20 "In9.Cu" signal "IN4")
		(22 "In10.Cu" signal "GND3")
		(2 "B.Cu" signal "BOTTOM")
		(9 "F.Adhes" user "F.Adhesive")
		(11 "B.Adhes" user "B.Adhesive")
		(13 "F.Paste" user "Package Geometry/Pastemask Top")
		(15 "B.Paste" user "Package Geometry/Pastemask Bottom")
		(5 "F.SilkS" user "Ref Des/Silkscreen Top")
		(7 "B.SilkS" user "Ref Des/Silkscreen Bottom")
		(1 "F.Mask" user "Board Geometry/Soldermask Top")
		(3 "B.Mask" user "Board Geometry/Soldermask Bottom")
		(17 "Dwgs.User" user "User.Drawings")
		(19 "Cmts.User" user "User.Comments")
		(21 "Eco1.User" user "User.Eco1")
		(23 "Eco2.User" user "User.Eco2")
		(25 "Edge.Cuts" user "Board Geometry/Outline")
		(27 "Margin" user)
		(31 "F.CrtYd" user "Package Geometry/Place Bound Top")
		(29 "B.CrtYd" user "Package Geometry/Place Bound Bottom")
		(35 "F.Fab" user "Ref Des/Assembly Top")
		(33 "B.Fab" user "Ref Des/Assembly Bottom")
	)
	(footprint ""
		(layer "B.Cu")
		(at 32.893 -29.972 -90)
		(property "Reference" "C210"
			(at 0 0 90)
			(layer "B.SilkS")
			(hide yes)
			(effects
				(font
					(size 1.27 1.27)
				)
				(justify mirror)
			)
		)
		(property "Value" ""
			(at 0 0 90)
			(layer "B.Fab")
			(effects
				(font
					(size 1.27 1.27)
				)
				(justify mirror)
			)
		)
		(duplicate_pad_numbers_are_jumpers no)
		(fp_line
			(start -0.7874 0.406146)
			(end 0.7874 0.406146)
			(stroke
				(width 0.1524)
				(type default)
			)
			(layer "B.SilkS")
		)
		(fp_line
			(start 0.7874 0.406146)
			(end 0.7874 -0.406146)
			(stroke
				(width 0.1524)
				(type default)
			)
			(layer "B.SilkS")
		)
		(fp_line
			(start -0.7874 -0.406146)
			(end -0.7874 0.406146)
			(stroke
				(width 0.1524)
				(type default)
			)
			(layer "B.SilkS")
		)
		(fp_line
			(start 0.7874 -0.406146)
			(end -0.7874 -0.406146)
			(stroke
				(width 0.1524)
				(type default)
			)
			(layer "B.SilkS")
		)
		(fp_line
			(start -0.67945 0.3048)
			(end -0.120396 0.3048)
			(stroke
				(width 0.1)
				(type default)
			)
			(layer "B.Fab")
		)
		(fp_line
			(start -0.120396 0.3048)
			(end -0.120396 0.2794)
			(stroke
				(width 0.1)
				(type default)
			)
			(layer "B.Fab")
		)
		(fp_line
			(start 0.120396 0.3048)
			(end 0.67945 0.3048)
			(stroke
				(width 0.1)
				(type default)
			)
			(layer "B.Fab")
		)
		(fp_line
			(start 0.67945 0.3048)
			(end 0.67945 -0.305054)
			(stroke
				(width 0.1)
				(type default)
			)
			(layer "B.Fab")
		)
		(fp_line
			(start -0.120396 0.2794)
			(end 0.12065 0.2794)
			(stroke
				(width 0.1)
				(type default)
			)
			(layer "B.Fab")
		)
		(fp_line
			(start 0.12065 0.2794)
			(end 0.120396 0.3048)
			(stroke
				(width 0.1)
				(type default)
			)
			(layer "B.Fab")
		)
		(fp_line
			(start -0.12065 -0.2794)
			(end -0.120396 -0.3048)
			(stroke
				(width 0.1)
				(type default)
			)
			(layer "B.Fab")
		)
		(fp_line
			(start 0.12065 -0.2794)
			(end -0.12065 -0.2794)
			(stroke
				(width 0.1)
				(type default)
			)
			(layer "B.Fab")
		)
		(fp_line
			(start -0.67945 -0.3048)
			(end -0.67945 0.3048)
			(stroke
				(width 0.1)
				(type default)
			)
			(layer "B.Fab")
		)
		(fp_line
			(start -0.120396 -0.3048)
			(end -0.67945 -0.3048)
			(stroke
				(width 0.1)
				(type default)
			)
			(layer "B.Fab")
		)
		(fp_line
			(start 0.12065 -0.305054)
			(end 0.12065 -0.2794)
			(stroke
				(width 0.1)
				(type default)
			)
			(layer "B.Fab")
		)
		(fp_line
			(start 0.67945 -0.305054)
			(end 0.12065 -0.305054)
			(stroke
				(width 0.1)
				(type default)
			)
			(layer "B.Fab")
		)
		(pad "1" smd circle
			(at 0.40005 0 90)
			(size 0 0)
			(layers "B.Cu" "B.Mask" "B.Paste")
			(net "V_DACB_IO")
		)
		(pad "2" smd circle
			(at -0.40005 0 90)
			(size 0 0)
			(layers "B.Cu" "B.Mask" "B.Paste")
			(net "GND")
		)
	)
	(footprint ""
		(layer "B.Cu")
		(at 58.726832 -52.58816)
		(property "Reference" "C97"
			(at 0 0 0)
			(layer "B.SilkS")
			(hide yes)
			(effects
				(font
					(size 1.27 1.27)
				)
				(justify mirror)
			)
		)
		(property "Value" ""
			(at 0 0 0)
			(layer "B.Fab")
			(effects
				(font
					(size 1.27 1.27)
				)
				(justify mirror)
			)
		)
		(duplicate_pad_numbers_are_jumpers no)
		(fp_line
			(start -0.7874 -0.4064)
			(end -0.7874 0.4064)
			(stroke
				(width 0.1524)
				(type default)
			)
			(layer "B.SilkS")
		)
		(fp_line
			(start -0.7874 0.4064)
			(end 0.7874 0.4064)
			(stroke
				(width 0.1524)
				(type default)
			)
			(layer "B.SilkS")
		)
		(fp_line
			(start 0.7874 -0.4064)
			(end -0.7874 -0.4064)
			(stroke
				(width 0.1524)
				(type default)
			)
			(layer "B.SilkS")
		)
		(fp_line
			(start 0.7874 0.4064)
			(end 0.7874 -0.4064)
			(stroke
				(width 0.1524)
				(type default)
			)
			(layer "B.SilkS")
		)
		(fp_line
			(start -0.67945 -0.3048)
			(end -0.67945 0.3048)
			(stroke
				(width 0.1)
				(type default)
			)
			(layer "B.Fab")
		)
		(fp_line
			(start -0.67945 0.3048)
			(end -0.120396 0.3048)
			(stroke
				(width 0.1)
				(type default)
			)
			(layer "B.Fab")
		)
		(fp_line
			(start -0.12065 -0.3048)
			(end -0.67945 -0.3048)
			(stroke
				(width 0.1)
				(type default)
			)
			(layer "B.Fab")
		)
		(fp_line
			(start -0.12065 -0.2794)
			(end -0.12065 -0.3048)
			(stroke
				(width 0.1)
				(type default)
			)
			(layer "B.Fab")
		)
		(fp_line
			(start -0.120396 0.2794)
			(end 0.12065 0.2794)
			(stroke
				(width 0.1)
				(type default)
			)
			(layer "B.Fab")
		)
		(fp_line
			(start -0.120396 0.3048)
			(end -0.120396 0.2794)
			(stroke
				(width 0.1)
				(type default)
			)
			(layer "B.Fab")
		)
		(fp_line
			(start 0.12065 -0.305054)
			(end 0.12065 -0.2794)
			(stroke
				(width 0.1)
				(type default)
			)
			(layer "B.Fab")
		)
		(fp_line
			(start 0.12065 -0.2794)
			(end -0.12065 -0.2794)
			(stroke
				(width 0.1)
				(type default)
			)
			(layer "B.Fab")
		)
		(fp_line
			(start 0.12065 0.2794)
			(end 0.12065 0.3048)
			(stroke
				(width 0.1)
				(type default)
			)
			(layer "B.Fab")
		)
		(fp_line
			(start 0.12065 0.3048)
			(end 0.67945 0.3048)
			(stroke
				(width 0.1)
				(type default)
			)
			(layer "B.Fab")
		)
		(fp_line
			(start 0.67945 -0.305054)
			(end 0.12065 -0.305054)
			(stroke
				(width 0.1)
				(type default)
			)
			(layer "B.Fab")
		)
		(fp_line
			(start 0.67945 0.3048)
			(end 0.67945 -0.305054)
			(stroke
				(width 0.1)
				(type default)
			)
			(layer "B.Fab")
		)
		(pad "1" smd circle
			(at 0.40005 0 180)
			(size 0 0)
			(layers "B.Cu" "B.Mask" "B.Paste")
			(net "P1V0_STBY_DP_VCC10A")
		)
		(pad "2" smd circle
			(at -0.40005 0 180)
			(size 0 0)
			(layers "B.Cu" "B.Mask" "B.Paste")
			(net "GND")
		)
	)
	(footprint ""
		(layer "B.Cu")
		(at 33.1089 -97.1042 90)
		(property "Reference" "U58"
			(at 0.1778 2.17043 270)
			(unlocked yes)
			(layer "B.SilkS")
			(effects
				(font
					(size 0.7874 0.5842)
					(thickness 0.1524)
				)
				(justify mirror)
			)
		)
		(property "Value" ""
			(at 0 0 90)
			(layer "B.Fab")
			(effects
				(font
					(size 1.27 1.27)
				)
				(justify mirror)
			)
		)
		(duplicate_pad_numbers_are_jumpers no)
		(fp_line
			(start 1.834896 -1.575054)
			(end 0.508 -1.575054)
			(stroke
				(width 0.1524)
				(type default)
			)
			(layer "B.SilkS")
		)
		(fp_line
			(start 0.508 -1.575054)
			(end 0 -1.016)
			(stroke
				(width 0.1524)
				(type default)
			)
			(layer "B.SilkS")
		)
		(fp_line
			(start -0.508 -1.575054)
			(end -1.834896 -1.575054)
			(stroke
				(width 0.1524)
				(type default)
			)
			(layer "B.SilkS")
		)
		(fp_line
			(start -1.834896 -1.575054)
			(end -1.834896 1.575054)
			(stroke
				(width 0.1524)
				(type default)
			)
			(layer "B.SilkS")
		)
		(fp_line
			(start 0 -1.016)
			(end -0.508 -1.575054)
			(stroke
				(width 0.1524)
				(type default)
			)
			(layer "B.SilkS")
		)
		(fp_line
			(start 1.834896 1.575054)
			(end 1.834896 -1.575054)
			(stroke
				(width 0.1524)
				(type default)
			)
			(layer "B.SilkS")
		)
		(fp_line
			(start -1.834896 1.575054)
			(end 1.834896 1.575054)
			(stroke
				(width 0.1524)
				(type default)
			)
			(layer "B.SilkS")
		)
		(fp_poly
			(pts
				(xy 3.003296 -1.45796) (xy 3.003296 -0.44196) (xy 1.987296 -0.94996)
			)
			(stroke
				(width 0)
				(type default)
			)
			(fill yes)
			(layer "B.SilkS")
		)
		(fp_line
			(start 0.824992 -1.575054)
			(end -0.824992 -1.575054)
			(stroke
				(width 0.1)
				(type default)
			)
			(layer "B.Fab")
		)
		(fp_line
			(start -0.824992 -1.575054)
			(end -0.824992 1.575054)
			(stroke
				(width 0.1)
				(type default)
			)
			(layer "B.Fab")
		)
		(fp_line
			(start 0.824992 1.575054)
			(end 0.824992 -1.575054)
			(stroke
				(width 0.1)
				(type default)
			)
			(layer "B.Fab")
		)
		(fp_line
			(start -0.824992 1.575054)
			(end 0.824992 1.575054)
			(stroke
				(width 0.1)
				(type default)
			)
			(layer "B.Fab")
		)
		(fp_poly
			(pts
				(xy 3.003296 -1.45796) (xy 3.003296 -0.44196) (xy 1.987296 -0.94996)
			)
			(stroke
				(width 0)
				(type default)
			)
			(fill yes)
			(layer "B.Fab")
		)
		(pad "1" smd rect
			(at 1.199896 -0.94996)
			(size 0.7112 1.016)
			(layers "B.Cu" "B.Mask" "B.Paste")
			(net "RST_BMC_SELF_HW_R3")
		)
		(pad "2" smd rect
			(at 1.199896 0)
			(size 0.7112 1.016)
			(layers "B.Cu" "B.Mask" "B.Paste")
			(net "RST_BMC_HW_R1")
		)
		(pad "3" smd rect
			(at 1.199896 0.94996)
			(size 0.7112 1.016)
			(layers "B.Cu" "B.Mask" "B.Paste")
			(net "GND")
		)
		(pad "4" smd rect
			(at -1.199896 0.94996)
			(size 0.7112 1.016)
			(layers "B.Cu" "B.Mask" "B.Paste")
			(net "RST_BMC_HW_OUT")
		)
		(pad "5" smd rect
			(at -1.199896 -0.94996)
			(size 0.7112 1.016)
			(layers "B.Cu" "B.Mask" "B.Paste")
			(net "P3V3_AUX")
		)
	)
	(footprint ""
		(layer "B.Cu")
		(at 10.40892 -94.6404 90)
		(property "Reference" "R607"
			(at 0 0 90)
			(layer "B.SilkS")
			(hide yes)
			(effects
				(font
					(size 1.27 1.27)
				)
				(justify mirror)
			)
		)
		(property "Value" ""
			(at 0 0 90)
			(layer "B.Fab")
			(effects
				(font
					(size 1.27 1.27)
				)
				(justify mirror)
			)
		)
		(duplicate_pad_numbers_are_jumpers no)
		(fp_line
			(start 0.7874 -0.4064)
			(end -0.7874 -0.4064)
			(stroke
				(width 0.1524)
				(type default)
			)
			(layer "B.SilkS")
		)
		(fp_line
			(start -0.7874 -0.4064)
			(end -0.7874 0.4064)
			(stroke
				(width 0.1524)
				(type default)
			)
			(layer "B.SilkS")
		)
		(fp_line
			(start 0.7874 0.4064)
			(end 0.7874 -0.4064)
			(stroke
				(width 0.1524)
				(type default)
			)
			(layer "B.SilkS")
		)
		(fp_line
			(start -0.7874 0.4064)
			(end 0.7874 0.4064)
			(stroke
				(width 0.1524)
				(type default)
			)
			(layer "B.SilkS")
		)
		(fp_line
			(start 0.67945 -0.305054)
			(end 0.12065 -0.305054)
			(stroke
				(width 0.1)
				(type default)
			)
			(layer "B.Fab")
		)
		(fp_line
			(start 0.12065 -0.305054)
			(end 0.12065 -0.2794)
			(stroke
				(width 0.1)
				(type default)
			)
			(layer "B.Fab")
		)
		(fp_line
			(start -0.12065 -0.3048)
			(end -0.67945 -0.3048)
			(stroke
				(width 0.1)
				(type default)
			)
			(layer "B.Fab")
		)
		(fp_line
			(start -0.67945 -0.3048)
			(end -0.67945 0.3048)
			(stroke
				(width 0.1)
				(type default)
			)
			(layer "B.Fab")
		)
		(fp_line
			(start 0.12065 -0.2794)
			(end -0.12065 -0.2794)
			(stroke
				(width 0.1)
				(type default)
			)
			(layer "B.Fab")
		)
		(fp_line
			(start -0.12065 -0.2794)
			(end -0.12065 -0.3048)
			(stroke
				(width 0.1)
				(type default)
			)
			(layer "B.Fab")
		)
		(fp_line
			(start 0.12065 0.2794)
			(end 0.12065 0.3048)
			(stroke
				(width 0.1)
				(type default)
			)
			(layer "B.Fab")
		)
		(fp_line
			(start -0.120396 0.2794)
			(end 0.12065 0.2794)
			(stroke
				(width 0.1)
				(type default)
			)
			(layer "B.Fab")
		)
		(fp_line
			(start 0.67945 0.3048)
			(end 0.67945 -0.305054)
			(stroke
				(width 0.1)
				(type default)
			)
			(layer "B.Fab")
		)
		(fp_line
			(start 0.12065 0.3048)
			(end 0.67945 0.3048)
			(stroke
				(width 0.1)
				(type default)
			)
			(layer "B.Fab")
		)
		(fp_line
			(start -0.120396 0.3048)
			(end -0.120396 0.2794)
			(stroke
				(width 0.1)
				(type default)
			)
			(layer "B.Fab")
		)
		(fp_line
			(start -0.67945 0.3048)
			(end -0.120396 0.3048)
			(stroke
				(width 0.1)
				(type default)
			)
			(layer "B.Fab")
		)
		(pad "1" smd circle
			(at 0.40005 0 270)
			(size 0 0)
			(layers "B.Cu" "B.Mask" "B.Paste")
			(net "P3V3_AUX")
		)
		(pad "2" smd circle
			(at -0.40005 0 270)
			(size 0 0)
			(layers "B.Cu" "B.Mask" "B.Paste")
			(net "BMC_CPLD_GPIO_12")
		)
	)
	(footprint ""
		(layer "B.Cu")
		(at 58.547 -34.671 90)
		(property "Reference" "R143"
			(at 0 0 90)
			(layer "B.SilkS")
			(hide yes)
			(effects
				(font
					(size 1.27 1.27)
				)
				(justify mirror)
			)
		)
		(property "Value" ""
			(at 0 0 90)
			(layer "B.Fab")
			(effects
				(font
					(size 1.27 1.27)
				)
				(justify mirror)
			)
		)
		(duplicate_pad_numbers_are_jumpers no)
		(fp_line
			(start 0.7874 -0.4064)
			(end -0.7874 -0.4064)
			(stroke
				(width 0.1524)
				(type default)
			)
			(layer "B.SilkS")
		)
		(fp_line
			(start -0.7874 -0.4064)
			(end -0.7874 0.4064)
			(stroke
				(width 0.1524)
				(type default)
			)
			(layer "B.SilkS")
		)
		(fp_line
			(start 0.7874 0.4064)
			(end 0.7874 -0.4064)
			(stroke
				(width 0.1524)
				(type default)
			)
			(layer "B.SilkS")
		)
		(fp_line
			(start -0.7874 0.4064)
			(end 0.7874 0.4064)
			(stroke
				(width 0.1524)
				(type default)
			)
			(layer "B.SilkS")
		)
		(fp_line
			(start 0.67945 -0.305054)
			(end 0.12065 -0.305054)
			(stroke
				(width 0.1)
				(type default)
			)
			(layer "B.Fab")
		)
		(fp_line
			(start 0.12065 -0.305054)
			(end 0.12065 -0.2794)
			(stroke
				(width 0.1)
				(type default)
			)
			(layer "B.Fab")
		)
		(fp_line
			(start -0.12065 -0.3048)
			(end -0.67945 -0.3048)
			(stroke
				(width 0.1)
				(type default)
			)
			(layer "B.Fab")
		)
		(fp_line
			(start -0.67945 -0.3048)
			(end -0.67945 0.3048)
			(stroke
				(width 0.1)
				(type default)
			)
			(layer "B.Fab")
		)
		(fp_line
			(start 0.12065 -0.2794)
			(end -0.12065 -0.2794)
			(stroke
				(width 0.1)
				(type default)
			)
			(layer "B.Fab")
		)
		(fp_line
			(start -0.12065 -0.2794)
			(end -0.12065 -0.3048)
			(stroke
				(width 0.1)
				(type default)
			)
			(layer "B.Fab")
		)
		(fp_line
			(start 0.12065 0.2794)
			(end 0.12065 0.3048)
			(stroke
				(width 0.1)
				(type default)
			)
			(layer "B.Fab")
		)
		(fp_line
			(start -0.120396 0.2794)
			(end 0.12065 0.2794)
			(stroke
				(width 0.1)
				(type default)
			)
			(layer "B.Fab")
		)
		(fp_line
			(start 0.67945 0.3048)
			(end 0.67945 -0.305054)
			(stroke
				(width 0.1)
				(type default)
			)
			(layer "B.Fab")
		)
		(fp_line
			(start 0.12065 0.3048)
			(end 0.67945 0.3048)
			(stroke
				(width 0.1)
				(type default)
			)
			(layer "B.Fab")
		)
		(fp_line
			(start -0.120396 0.3048)
			(end -0.120396 0.2794)
			(stroke
				(width 0.1)
				(type default)
			)
			(layer "B.Fab")
		)
		(fp_line
			(start -0.67945 0.3048)
			(end -0.120396 0.3048)
			(stroke
				(width 0.1)
				(type default)
			)
			(layer "B.Fab")
		)
		(pad "1" smd circle
			(at 0.40005 0 270)
			(size 0 0)
			(layers "B.Cu" "B.Mask" "B.Paste")
			(net "SMB_BMC_MM6_R_SDA")
		)
		(pad "2" smd circle
			(at -0.40005 0 270)
			(size 0 0)
			(layers "B.Cu" "B.Mask" "B.Paste")
			(net "SMB_BMC_MM6_SDA")
		)
	)
	(footprint ""
		(layer "B.Cu")
		(at 29.972 -100.838 180)
		(property "Reference" "C145"
			(at 0 0 0)
			(layer "B.SilkS")
			(hide yes)
			(effects
				(font
					(size 1.27 1.27)
				)
				(justify mirror)
			)
		)
		(property "Value" ""
			(at 0 0 0)
			(layer "B.Fab")
			(effects
				(font
					(size 1.27 1.27)
				)
				(justify mirror)
			)
		)
		(duplicate_pad_numbers_are_jumpers no)
		(fp_line
			(start 0.7874 0.4064)
			(end 0.7874 -0.4064)
			(stroke
				(width 0.1524)
				(type default)
			)
			(layer "B.SilkS")
		)
		(fp_line
			(start 0.7874 -0.4064)
			(end -0.7874 -0.4064)
			(stroke
				(width 0.1524)
				(type default)
			)
			(layer "B.SilkS")
		)
		(fp_line
			(start -0.7874 0.4064)
			(end 0.7874 0.4064)
			(stroke
				(width 0.1524)
				(type default)
			)
			(layer "B.SilkS")
		)
		(fp_line
			(start -0.7874 -0.4064)
			(end -0.7874 0.4064)
			(stroke
				(width 0.1524)
				(type default)
			)
			(layer "B.SilkS")
		)
		(fp_line
			(start 0.67945 0.3048)
			(end 0.67945 -0.305054)
			(stroke
				(width 0.1)
				(type default)
			)
			(layer "B.Fab")
		)
		(fp_line
			(start 0.67945 -0.305054)
			(end 0.12065 -0.305054)
			(stroke
				(width 0.1)
				(type default)
			)
			(layer "B.Fab")
		)
		(fp_line
			(start 0.12065 0.3048)
			(end 0.67945 0.3048)
			(stroke
				(width 0.1)
				(type default)
			)
			(layer "B.Fab")
		)
		(fp_line
			(start 0.12065 0.2794)
			(end 0.12065 0.3048)
			(stroke
				(width 0.1)
				(type default)
			)
			(layer "B.Fab")
		)
		(fp_line
			(start 0.12065 -0.2794)
			(end -0.12065 -0.2794)
			(stroke
				(width 0.1)
				(type default)
			)
			(layer "B.Fab")
		)
		(fp_line
			(start 0.12065 -0.305054)
			(end 0.12065 -0.2794)
			(stroke
				(width 0.1)
				(type default)
			)
			(layer "B.Fab")
		)
		(fp_line
			(start -0.120396 0.3048)
			(end -0.120396 0.2794)
			(stroke
				(width 0.1)
				(type default)
			)
			(layer "B.Fab")
		)
		(fp_line
			(start -0.120396 0.2794)
			(end 0.12065 0.2794)
			(stroke
				(width 0.1)
				(type default)
			)
			(layer "B.Fab")
		)
		(fp_line
			(start -0.12065 -0.2794)
			(end -0.12065 -0.3048)
			(stroke
				(width 0.1)
				(type default)
			)
			(layer "B.Fab")
		)
		(fp_line
			(start -0.12065 -0.3048)
			(end -0.67945 -0.3048)
			(stroke
				(width 0.1)
				(type default)
			)
			(layer "B.Fab")
		)
		(fp_line
			(start -0.67945 0.3048)
			(end -0.120396 0.3048)
			(stroke
				(width 0.1)
				(type default)
			)
			(layer "B.Fab")
		)
		(fp_line
			(start -0.67945 -0.3048)
			(end -0.67945 0.3048)
			(stroke
				(width 0.1)
				(type default)
			)
			(layer "B.Fab")
		)
		(pad "1" smd circle
			(at 0.40005 0)
			(size 0 0)
			(layers "B.Cu" "B.Mask" "B.Paste")
			(net "P3V3_AUX")
		)
		(pad "2" smd circle
			(at -0.40005 0)
			(size 0 0)
			(layers "B.Cu" "B.Mask" "B.Paste")
			(net "GND")
		)
	)
)
